# T6G (Grand Teton) — schematic netlist excerpt (pin names and nets, part order shuffled) for the footprints in the layout excerpt that follows; sources: Cadence DE-HDL packaged netlist, KiCad conversion of 04192023_DAF0TMB3IC0_F0TG_MB_C_brd_V02_OCP.brd

R2531  Q_RES  0 5% CHIP  pkg 0402LF  page 242 : A = MB0_P12V_STBY_PWRGD ; B = FM_P12V_HSC_EN_R
R8118  Q_RES  33.2 1% CHIP  pkg 0402LF  page 268 : A = FM_UV_ADR_TRIGGER_N_R2 ; B = FM_UV_ADR_TRIGGER_N
C714  Q_CAP_DIFFBUS  DIFF BUS_0.22UF 6.3V 20% X6S  pkg C0201  page 66 : \1\ = P5E_CPU1_P1_TX_C_DN<13> ; \2\ = P5E_CPU1_P1_TX_DN<13>

(kicad_pcb
	(version 20260206)
	(generator "pcbnew")
	(generator_version "10.0")
	(general
		(thickness 1.6)
		(legacy_teardrops no)
	)
	(paper "A4")
	(title_block
		(title "04192023_DAF0TMB3IC0_F0TG_MB_C_brd_V02_OCP.brd")
		(comment 1 "Grand Teton / footprints 3774-3776 of 8354")
	)
	(layers
		(0 "F.Cu" signal "TOP")
		(4 "In1.Cu" signal "GND")
		(6 "In2.Cu" signal "IN1")
		(8 "In3.Cu" signal "GND1")
		(10 "In4.Cu" signal "IN2")
		(12 "In5.Cu" signal "GND2")
		(14 "In6.Cu" signal "IN3")
		(16 "In7.Cu" signal "GND3")
		(18 "In8.Cu" signal "VCC")
		(20 "In9.Cu" signal "VCC1")
		(22 "In10.Cu" signal "GND4")
		(24 "In11.Cu" signal "IN4")
		(26 "In12.Cu" signal "GND5")
		(28 "In13.Cu" signal "IN5")
		(30 "In14.Cu" signal "GND6")
		(32 "In15.Cu" signal "IN6")
		(34 "In16.Cu" signal "GND7")
		(2 "B.Cu" signal "BOTTOM")
		(9 "F.Adhes" user "F.Adhesive")
		(11 "B.Adhes" user "B.Adhesive")
		(13 "F.Paste" user "Package Geometry/Pastemask Top")
		(15 "B.Paste" user "Package Geometry/Pastemask Bottom")
		(5 "F.SilkS" user "Ref Des/Silkscreen Top")
		(7 "B.SilkS" user "Ref Des/Silkscreen Bottom")
		(1 "F.Mask" user "Board Geometry/Soldermask Top")
		(3 "B.Mask" user "Board Geometry/Soldermask Bottom")
		(17 "Dwgs.User" user "User.Drawings")
		(19 "Cmts.User" user "User.Comments")
		(21 "Eco1.User" user "User.Eco1")
		(23 "Eco2.User" user "User.Eco2")
		(25 "Edge.Cuts" user "Board Geometry/Outline")
		(27 "Margin" user)
		(31 "F.CrtYd" user "Package Geometry/Place Bound Top")
		(29 "B.CrtYd" user "Package Geometry/Place Bound Bottom")
		(35 "F.Fab" user "Ref Des/Assembly Top")
		(33 "B.Fab" user "Ref Des/Assembly Bottom")
	)
	(footprint ""
		(layer "F.Cu")
		(at 213.8426 -138.124438 -90)
		(property "Reference" "R2531"
			(at 0 0 270)
			(layer "F.SilkS")
			(hide yes)
			(effects
				(font
					(size 1.27 1.27)
				)
			)
		)
		(property "Value" ""
			(at 0 0 270)
			(layer "F.Fab")
			(effects
				(font
					(size 1.27 1.27)
				)
			)
		)
		(duplicate_pad_numbers_are_jumpers no)
		(fp_line
			(start -0.7874 0.4064)
			(end -0.7874 -0.4064)
			(stroke
				(width 0.1524)
				(type default)
			)
			(layer "F.SilkS")
		)
		(fp_line
			(start 0.7874 0.4064)
			(end -0.7874 0.4064)
			(stroke
				(width 0.1524)
				(type default)
			)
			(layer "F.SilkS")
		)
		(fp_line
			(start -0.7874 -0.4064)
			(end 0.7874 -0.4064)
			(stroke
				(width 0.1524)
				(type default)
			)
			(layer "F.SilkS")
		)
		(fp_line
			(start 0.7874 -0.4064)
			(end 0.7874 0.4064)
			(stroke
				(width 0.1524)
				(type default)
			)
			(layer "F.SilkS")
		)
		(fp_line
			(start -0.67945 0.3048)
			(end -0.67945 -0.305054)
			(stroke
				(width 0.1)
				(type default)
			)
			(layer "F.Fab")
		)
		(fp_line
			(start -0.12065 0.3048)
			(end -0.67945 0.3048)
			(stroke
				(width 0.1)
				(type default)
			)
			(layer "F.Fab")
		)
		(fp_line
			(start 0.120396 0.3048)
			(end 0.120396 0.2794)
			(stroke
				(width 0.1)
				(type default)
			)
			(layer "F.Fab")
		)
		(fp_line
			(start 0.67945 0.3048)
			(end 0.120396 0.3048)
			(stroke
				(width 0.1)
				(type default)
			)
			(layer "F.Fab")
		)
		(fp_line
			(start -0.12065 0.2794)
			(end -0.12065 0.3048)
			(stroke
				(width 0.1)
				(type default)
			)
			(layer "F.Fab")
		)
		(fp_line
			(start 0.120396 0.2794)
			(end -0.12065 0.2794)
			(stroke
				(width 0.1)
				(type default)
			)
			(layer "F.Fab")
		)
		(fp_line
			(start -0.12065 -0.2794)
			(end 0.12065 -0.2794)
			(stroke
				(width 0.1)
				(type default)
			)
			(layer "F.Fab")
		)
		(fp_line
			(start 0.12065 -0.2794)
			(end 0.12065 -0.3048)
			(stroke
				(width 0.1)
				(type default)
			)
			(layer "F.Fab")
		)
		(fp_line
			(start 0.12065 -0.3048)
			(end 0.67945 -0.3048)
			(stroke
				(width 0.1)
				(type default)
			)
			(layer "F.Fab")
		)
		(fp_line
			(start 0.67945 -0.3048)
			(end 0.67945 0.3048)
			(stroke
				(width 0.1)
				(type default)
			)
			(layer "F.Fab")
		)
		(fp_line
			(start -0.67945 -0.305054)
			(end -0.12065 -0.305054)
			(stroke
				(width 0.1)
				(type default)
			)
			(layer "F.Fab")
		)
		(fp_line
			(start -0.12065 -0.305054)
			(end -0.12065 -0.2794)
			(stroke
				(width 0.1)
				(type default)
			)
			(layer "F.Fab")
		)
		(pad "1" smd circle
			(at -0.40005 0 270)
			(size 0 0)
			(layers "F.Cu" "F.Mask" "F.Paste")
			(net "MB0_P12V_STBY_PWRGD")
		)
		(pad "2" smd circle
			(at 0.40005 0 270)
			(size 0 0)
			(layers "F.Cu" "F.Mask" "F.Paste")
			(net "FM_P12V_HSC_EN_R")
		)
	)
	(footprint ""
		(layer "F.Cu")
		(at 101.958902 -370.57203 -90)
		(property "Reference" "C714"
			(at 0 0 270)
			(layer "F.SilkS")
			(hide yes)
			(effects
				(font
					(size 1.27 1.27)
				)
			)
		)
		(property "Value" ""
			(at 0 0 270)
			(layer "F.Fab")
			(effects
				(font
					(size 1.27 1.27)
				)
			)
		)
		(duplicate_pad_numbers_are_jumpers no)
		(fp_line
			(start -0.299974 0.150114)
			(end -0.299974 -0.150114)
			(stroke
				(width 0.1)
				(type default)
			)
			(layer "F.Fab")
		)
		(fp_line
			(start 0.299974 0.150114)
			(end -0.299974 0.150114)
			(stroke
				(width 0.1)
				(type default)
			)
			(layer "F.Fab")
		)
		(fp_line
			(start -0.299974 -0.150114)
			(end 0.299974 -0.150114)
			(stroke
				(width 0.1)
				(type default)
			)
			(layer "F.Fab")
		)
		(fp_line
			(start 0.299974 -0.150114)
			(end 0.299974 0.150114)
			(stroke
				(width 0.1)
				(type default)
			)
			(layer "F.Fab")
		)
		(pad "1" smd rect
			(at -0.2667 0 270)
			(size 0.3048 0.381)
			(layers "F.Cu" "F.Mask" "F.Paste")
			(net "P5E_CPU1_P1_TX_C_DN<13>")
		)
		(pad "2" smd rect
			(at 0.2667 0 270)
			(size 0.3048 0.381)
			(layers "F.Cu" "F.Mask" "F.Paste")
			(net "P5E_CPU1_P1_TX_DN<13>")
		)
	)
	(footprint ""
		(layer "F.Cu")
		(at 148.642324 -115.377468)
		(property "Reference" "R8118"
			(at 0 0 0)
			(layer "F.SilkS")
			(hide yes)
			(effects
				(font
					(size 1.27 1.27)
				)
			)
		)
		(property "Value" ""
			(at 0 0 0)
			(layer "F.Fab")
			(effects
				(font
					(size 1.27 1.27)
				)
			)
		)
		(duplicate_pad_numbers_are_jumpers no)
		(fp_line
			(start -0.7874 -0.4064)
			(end 0.7874 -0.4064)
			(stroke
				(width 0.1524)
				(type default)
			)
			(layer "F.SilkS")
		)
		(fp_line
			(start -0.7874 0.4064)
			(end -0.7874 -0.4064)
			(stroke
				(width 0.1524)
				(type default)
			)
			(layer "F.SilkS")
		)
		(fp_line
			(start 0.7874 -0.4064)
			(end 0.7874 0.4064)
			(stroke
				(width 0.1524)
				(type default)
			)
			(layer "F.SilkS")
		)
		(fp_line
			(start 0.7874 0.4064)
			(end -0.7874 0.4064)
			(stroke
				(width 0.1524)
				(type default)
			)
			(layer "F.SilkS")
		)
		(fp_line
			(start -0.67945 -0.305054)
			(end -0.12065 -0.305054)
			(stroke
				(width 0.1)
				(type default)
			)
			(layer "F.Fab")
		)
		(fp_line
			(start -0.67945 0.3048)
			(end -0.67945 -0.305054)
			(stroke
				(width 0.1)
				(type default)
			)
			(layer "F.Fab")
		)
		(fp_line
			(start -0.12065 -0.305054)
			(end -0.12065 -0.2794)
			(stroke
				(width 0.1)
				(type default)
			)
			(layer "F.Fab")
		)
		(fp_line
			(start -0.12065 -0.2794)
			(end 0.12065 -0.2794)
			(stroke
				(width 0.1)
				(type default)
			)
			(layer "F.Fab")
		)
		(fp_line
			(start -0.12065 0.2794)
			(end -0.12065 0.3048)
			(stroke
				(width 0.1)
				(type default)
			)
			(layer "F.Fab")
		)
		(fp_line
			(start -0.12065 0.3048)
			(end -0.67945 0.3048)
			(stroke
				(width 0.1)
				(type default)
			)
			(layer "F.Fab")
		)
		(fp_line
			(start 0.120396 0.2794)
			(end -0.12065 0.2794)
			(stroke
				(width 0.1)
				(type default)
			)
			(layer "F.Fab")
		)
		(fp_line
			(start 0.120396 0.3048)
			(end 0.120396 0.2794)
			(stroke
				(width 0.1)
				(type default)
			)
			(layer "F.Fab")
		)
		(fp_line
			(start 0.12065 -0.3048)
			(end 0.67945 -0.3048)
			(stroke
				(width 0.1)
				(type default)
			)
			(layer "F.Fab")
		)
		(fp_line
			(start 0.12065 -0.2794)
			(end 0.12065 -0.3048)
			(stroke
				(width 0.1)
				(type default)
			)
			(layer "F.Fab")
		)
		(fp_line
			(start 0.67945 -0.3048)
			(end 0.67945 0.3048)
			(stroke
				(width 0.1)
				(type default)
			)
			(layer "F.Fab")
		)
		(fp_line
			(start 0.67945 0.3048)
			(end 0.120396 0.3048)
			(stroke
				(width 0.1)
				(type default)
			)
			(layer "F.Fab")
		)
		(pad "1" smd circle
			(at -0.40005 0)
			(size 0 0)
			(layers "F.Cu" "F.Mask" "F.Paste")
			(net "FM_UV_ADR_TRIGGER_N_R2")
		)
		(pad "2" smd circle
			(at 0.40005 0)
			(size 0 0)
			(layers "F.Cu" "F.Mask" "F.Paste")
			(net "FM_UV_ADR_TRIGGER_N")
		)
	)
)
